(kicad_pcb
	(version 20260206)
	(generator "pcbnew")
	(generator_version "10.0")
	(general
		(thickness 1.6)
		(legacy_teardrops no)
	)
	(paper "A4")
	(title_block
		(title "01162023_DA0F0TEBIF0_F0T_Expander_BD_F_brd_V02_OCP.brd")
		(comment 1 "Grand Teton / footprints 731-736 of 9728")
	)
	(layers
		(0 "F.Cu" signal "TOP")
		(4 "In1.Cu" signal "GND")
		(6 "In2.Cu" signal "VCC")
		(8 "In3.Cu" signal "VCC1")
		(10 "In4.Cu" signal "GND1")
		(12 "In5.Cu" signal "IN1")
		(14 "In6.Cu" signal "GND2")
		(16 "In7.Cu" signal "IN2")
		(18 "In8.Cu" signal "GND3")
		(20 "In9.Cu" signal "IN3")
		(22 "In10.Cu" signal "GND4")
		(24 "In11.Cu" signal "IN4")
		(26 "In12.Cu" signal "GND5")
		(28 "In13.Cu" signal "IN5")
		(30 "In14.Cu" signal "GND6")
		(32 "In15.Cu" signal "IN6")
		(34 "In16.Cu" signal "GND7")
		(2 "B.Cu" signal "BOTTOM")
		(9 "F.Adhes" user "F.Adhesive")
		(11 "B.Adhes" user "B.Adhesive")
		(13 "F.Paste" user "Package Geometry/Pastemask Top")
		(15 "B.Paste" user "Package Geometry/Pastemask Bottom")
		(5 "F.SilkS" user "Ref Des/Silkscreen Top")
		(7 "B.SilkS" user "Ref Des/Silkscreen Bottom")
		(1 "F.Mask" user "Board Geometry/Soldermask Top")
		(3 "B.Mask" user "Board Geometry/Soldermask Bottom")
		(17 "Dwgs.User" user "User.Drawings")
		(19 "Cmts.User" user "User.Comments")
		(21 "Eco1.User" user "User.Eco1")
		(23 "Eco2.User" user "User.Eco2")
		(25 "Edge.Cuts" user "Board Geometry/Outline")
		(27 "Margin" user)
		(31 "F.CrtYd" user "Package Geometry/Place Bound Top")
		(29 "B.CrtYd" user "Package Geometry/Place Bound Bottom")
		(35 "F.Fab" user "Ref Des/Assembly Top")
		(33 "B.Fab" user "Ref Des/Assembly Bottom")
	)
	(footprint ""
		(layer "F.Cu")
		(at 369.495578 -88.356694 180)
		(property "Reference" "R1611"
			(at 0 0 180)
			(layer "F.SilkS")
			(hide yes)
			(effects
				(font
					(size 1.27 1.27)
				)
			)
		)
		(property "Value" ""
			(at 0 0 180)
			(layer "F.Fab")
			(effects
				(font
					(size 1.27 1.27)
				)
			)
		)
		(duplicate_pad_numbers_are_jumpers no)
		(fp_line
			(start 0.7874 0.4064)
			(end -0.7874 0.4064)
			(stroke
				(width 0.1524)
				(type default)
			)
			(layer "F.SilkS")
		)
		(fp_line
			(start 0.7874 -0.4064)
			(end 0.7874 0.4064)
			(stroke
				(width 0.1524)
				(type default)
			)
			(layer "F.SilkS")
		)
		(fp_line
			(start -0.7874 0.4064)
			(end -0.7874 -0.4064)
			(stroke
				(width 0.1524)
				(type default)
			)
			(layer "F.SilkS")
		)
		(fp_line
			(start -0.7874 -0.4064)
			(end 0.7874 -0.4064)
			(stroke
				(width 0.1524)
				(type default)
			)
			(layer "F.SilkS")
		)
		(fp_line
			(start 0.67945 0.3048)
			(end 0.120396 0.3048)
			(stroke
				(width 0.1)
				(type default)
			)
			(layer "F.Fab")
		)
		(fp_line
			(start 0.67945 -0.3048)
			(end 0.67945 0.3048)
			(stroke
				(width 0.1)
				(type default)
			)
			(layer "F.Fab")
		)
		(fp_line
			(start 0.12065 -0.2794)
			(end 0.12065 -0.3048)
			(stroke
				(width 0.1)
				(type default)
			)
			(layer "F.Fab")
		)
		(fp_line
			(start 0.12065 -0.3048)
			(end 0.67945 -0.3048)
			(stroke
				(width 0.1)
				(type default)
			)
			(layer "F.Fab")
		)
		(fp_line
			(start 0.120396 0.3048)
			(end 0.120396 0.2794)
			(stroke
				(width 0.1)
				(type default)
			)
			(layer "F.Fab")
		)
		(fp_line
			(start 0.120396 0.2794)
			(end -0.12065 0.2794)
			(stroke
				(width 0.1)
				(type default)
			)
			(layer "F.Fab")
		)
		(fp_line
			(start -0.12065 0.3048)
			(end -0.67945 0.3048)
			(stroke
				(width 0.1)
				(type default)
			)
			(layer "F.Fab")
		)
		(fp_line
			(start -0.12065 0.2794)
			(end -0.12065 0.3048)
			(stroke
				(width 0.1)
				(type default)
			)
			(layer "F.Fab")
		)
		(fp_line
			(start -0.12065 -0.2794)
			(end 0.12065 -0.2794)
			(stroke
				(width 0.1)
				(type default)
			)
			(layer "F.Fab")
		)
		(fp_line
			(start -0.12065 -0.305054)
			(end -0.12065 -0.2794)
			(stroke
				(width 0.1)
				(type default)
			)
			(layer "F.Fab")
		)
		(fp_line
			(start -0.67945 0.3048)
			(end -0.67945 -0.305054)
			(stroke
				(width 0.1)
				(type default)
			)
			(layer "F.Fab")
		)
		(fp_line
			(start -0.67945 -0.305054)
			(end -0.12065 -0.305054)
			(stroke
				(width 0.1)
				(type default)
			)
			(layer "F.Fab")
		)
		(pad "1" smd circle
			(at -0.40005 0 180)
			(size 0 0)
			(layers "F.Cu" "F.Mask" "F.Paste")
			(net "P3V3_AUX")
		)
		(pad "2" smd circle
			(at 0.40005 0 180)
			(size 0 0)
			(layers "F.Cu" "F.Mask" "F.Paste")
			(net "SMB_BIC_I2C9_MUX1_SSD15_R_SDA")
		)
	)
	(footprint ""
		(layer "F.Cu")
		(at 330.646278 -58.323734)
		(property "Reference" "PC425"
			(at 0 0 0)
			(layer "F.SilkS")
			(hide yes)
			(effects
				(font
					(size 1.27 1.27)
				)
			)
		)
		(property "Value" ""
			(at 0 0 0)
			(layer "F.Fab")
			(effects
				(font
					(size 1.27 1.27)
				)
			)
		)
		(duplicate_pad_numbers_are_jumpers no)
		(fp_line
			(start -1.524 -0.762)
			(end 1.524 -0.762)
			(stroke
				(width 0.1524)
				(type default)
			)
			(layer "F.SilkS")
		)
		(fp_line
			(start -1.524 0.762)
			(end -1.524 -0.762)
			(stroke
				(width 0.1524)
				(type default)
			)
			(layer "F.SilkS")
		)
		(fp_line
			(start 1.524 -0.762)
			(end 1.524 0.762)
			(stroke
				(width 0.1524)
				(type default)
			)
			(layer "F.SilkS")
		)
		(fp_line
			(start 1.524 0.762)
			(end -1.524 0.762)
			(stroke
				(width 0.1524)
				(type default)
			)
			(layer "F.SilkS")
		)
		(fp_line
			(start -1.1049 -0.724916)
			(end -1.1049 0.724916)
			(stroke
				(width 0.1)
				(type default)
			)
			(layer "F.Fab")
		)
		(fp_line
			(start -1.1049 0.724916)
			(end 1.1049 0.724916)
			(stroke
				(width 0.1)
				(type default)
			)
			(layer "F.Fab")
		)
		(fp_line
			(start 1.1049 -0.724916)
			(end -1.1049 -0.724916)
			(stroke
				(width 0.1)
				(type default)
			)
			(layer "F.Fab")
		)
		(fp_line
			(start 1.1049 0.724916)
			(end 1.1049 -0.724916)
			(stroke
				(width 0.1)
				(type default)
			)
			(layer "F.Fab")
		)
		(pad "1" smd rect
			(at -0.889 0 180)
			(size 1.016 1.27)
			(layers "F.Cu" "F.Mask" "F.Paste")
			(net "GND")
		)
		(pad "2" smd rect
			(at 0.889 0 180)
			(size 1.016 1.27)
			(layers "F.Cu" "F.Mask" "F.Paste")
			(net "P12V_AUX")
		)
	)
	(footprint ""
		(layer "F.Cu")
		(at 319.39484 -59.577986 90)
		(property "Reference" "PC591"
			(at 0 0 90)
			(layer "F.SilkS")
			(hide yes)
			(effects
				(font
					(size 1.27 1.27)
				)
			)
		)
		(property "Value" ""
			(at 0 0 90)
			(layer "F.Fab")
			(effects
				(font
					(size 1.27 1.27)
				)
			)
		)
		(duplicate_pad_numbers_are_jumpers no)
		(fp_line
			(start 0.7874 -0.4064)
			(end 0.7874 0.4064)
			(stroke
				(width 0.1524)
				(type default)
			)
			(layer "F.SilkS")
		)
		(fp_line
			(start -0.7874 -0.4064)
			(end 0.7874 -0.4064)
			(stroke
				(width 0.1524)
				(type default)
			)
			(layer "F.SilkS")
		)
		(fp_line
			(start 0.7874 0.4064)
			(end -0.7874 0.4064)
			(stroke
				(width 0.1524)
				(type default)
			)
			(layer "F.SilkS")
		)
		(fp_line
			(start -0.7874 0.4064)
			(end -0.7874 -0.4064)
			(stroke
				(width 0.1524)
				(type default)
			)
			(layer "F.SilkS")
		)
		(fp_line
			(start -0.12065 -0.305054)
			(end -0.12065 -0.2794)
			(stroke
				(width 0.1)
				(type default)
			)
			(layer "F.Fab")
		)
		(fp_line
			(start -0.67945 -0.305054)
			(end -0.12065 -0.305054)
			(stroke
				(width 0.1)
				(type default)
			)
			(layer "F.Fab")
		)
		(fp_line
			(start 0.67945 -0.3048)
			(end 0.67945 0.3048)
			(stroke
				(width 0.1)
				(type default)
			)
			(layer "F.Fab")
		)
		(fp_line
			(start 0.12065 -0.3048)
			(end 0.67945 -0.3048)
			(stroke
				(width 0.1)
				(type default)
			)
			(layer "F.Fab")
		)
		(fp_line
			(start 0.12065 -0.2794)
			(end 0.12065 -0.3048)
			(stroke
				(width 0.1)
				(type default)
			)
			(layer "F.Fab")
		)
		(fp_line
			(start -0.12065 -0.2794)
			(end 0.12065 -0.2794)
			(stroke
				(width 0.1)
				(type default)
			)
			(layer "F.Fab")
		)
		(fp_line
			(start 0.120396 0.2794)
			(end -0.12065 0.2794)
			(stroke
				(width 0.1)
				(type default)
			)
			(layer "F.Fab")
		)
		(fp_line
			(start -0.12065 0.2794)
			(end -0.12065 0.3048)
			(stroke
				(width 0.1)
				(type default)
			)
			(layer "F.Fab")
		)
		(fp_line
			(start 0.67945 0.3048)
			(end 0.120396 0.3048)
			(stroke
				(width 0.1)
				(type default)
			)
			(layer "F.Fab")
		)
		(fp_line
			(start 0.120396 0.3048)
			(end 0.120396 0.2794)
			(stroke
				(width 0.1)
				(type default)
			)
			(layer "F.Fab")
		)
		(fp_line
			(start -0.12065 0.3048)
			(end -0.67945 0.3048)
			(stroke
				(width 0.1)
				(type default)
			)
			(layer "F.Fab")
		)
		(fp_line
			(start -0.67945 0.3048)
			(end -0.67945 -0.305054)
			(stroke
				(width 0.1)
				(type default)
			)
			(layer "F.Fab")
		)
		(pad "1" smd circle
			(at -0.40005 0 90)
			(size 0 0)
			(layers "F.Cu" "F.Mask" "F.Paste")
			(net "P3V3_SSD11_SS")
		)
		(pad "2" smd circle
			(at 0.40005 0 90)
			(size 0 0)
			(layers "F.Cu" "F.Mask" "F.Paste")
			(net "GND")
		)
	)
	(footprint ""
		(layer "F.Cu")
		(at 258.574286 -250.070874 -90)
		(property "Reference" "R1338"
			(at 0 0 270)
			(layer "F.SilkS")
			(hide yes)
			(effects
				(font
					(size 1.27 1.27)
				)
			)
		)
		(property "Value" ""
			(at 0 0 270)
			(layer "F.Fab")
			(effects
				(font
					(size 1.27 1.27)
				)
			)
		)
		(duplicate_pad_numbers_are_jumpers no)
		(fp_line
			(start -0.7874 0.4064)
			(end -0.7874 -0.4064)
			(stroke
				(width 0.1524)
				(type default)
			)
			(layer "F.SilkS")
		)
		(fp_line
			(start 0.7874 0.4064)
			(end -0.7874 0.4064)
			(stroke
				(width 0.1524)
				(type default)
			)
			(layer "F.SilkS")
		)
		(fp_line
			(start -0.7874 -0.4064)
			(end 0.7874 -0.4064)
			(stroke
				(width 0.1524)
				(type default)
			)
			(layer "F.SilkS")
		)
		(fp_line
			(start 0.7874 -0.4064)
			(end 0.7874 0.4064)
			(stroke
				(width 0.1524)
				(type default)
			)
			(layer "F.SilkS")
		)
		(fp_line
			(start -0.67945 0.3048)
			(end -0.67945 -0.305054)
			(stroke
				(width 0.1)
				(type default)
			)
			(layer "F.Fab")
		)
		(fp_line
			(start -0.12065 0.3048)
			(end -0.67945 0.3048)
			(stroke
				(width 0.1)
				(type default)
			)
			(layer "F.Fab")
		)
		(fp_line
			(start 0.120396 0.3048)
			(end 0.120396 0.2794)
			(stroke
				(width 0.1)
				(type default)
			)
			(layer "F.Fab")
		)
		(fp_line
			(start 0.67945 0.3048)
			(end 0.120396 0.3048)
			(stroke
				(width 0.1)
				(type default)
			)
			(layer "F.Fab")
		)
		(fp_line
			(start -0.12065 0.2794)
			(end -0.12065 0.3048)
			(stroke
				(width 0.1)
				(type default)
			)
			(layer "F.Fab")
		)
		(fp_line
			(start 0.120396 0.2794)
			(end -0.12065 0.2794)
			(stroke
				(width 0.1)
				(type default)
			)
			(layer "F.Fab")
		)
		(fp_line
			(start -0.12065 -0.2794)
			(end 0.12065 -0.2794)
			(stroke
				(width 0.1)
				(type default)
			)
			(layer "F.Fab")
		)
		(fp_line
			(start 0.12065 -0.2794)
			(end 0.12065 -0.3048)
			(stroke
				(width 0.1)
				(type default)
			)
			(layer "F.Fab")
		)
		(fp_line
			(start 0.12065 -0.3048)
			(end 0.67945 -0.3048)
			(stroke
				(width 0.1)
				(type default)
			)
			(layer "F.Fab")
		)
		(fp_line
			(start 0.67945 -0.3048)
			(end 0.67945 0.3048)
			(stroke
				(width 0.1)
				(type default)
			)
			(layer "F.Fab")
		)
		(fp_line
			(start -0.67945 -0.305054)
			(end -0.12065 -0.305054)
			(stroke
				(width 0.1)
				(type default)
			)
			(layer "F.Fab")
		)
		(fp_line
			(start -0.12065 -0.305054)
			(end -0.12065 -0.2794)
			(stroke
				(width 0.1)
				(type default)
			)
			(layer "F.Fab")
		)
		(pad "1" smd circle
			(at -0.40005 0 270)
			(size 0 0)
			(layers "F.Cu" "F.Mask" "F.Paste")
			(net "PEX2_MODE_SEL2")
		)
		(pad "2" smd circle
			(at 0.40005 0 270)
			(size 0 0)
			(layers "F.Cu" "F.Mask" "F.Paste")
			(net "P1V8_PEX")
		)
	)
	(footprint ""
		(layer "F.Cu")
		(at 353.822 -167.64)
		(property "Reference" "R4778"
			(at 0 0 0)
			(layer "F.SilkS")
			(hide yes)
			(effects
				(font
					(size 1.27 1.27)
				)
			)
		)
		(property "Value" ""
			(at 0 0 0)
			(layer "F.Fab")
			(effects
				(font
					(size 1.27 1.27)
				)
			)
		)
		(duplicate_pad_numbers_are_jumpers no)
		(fp_line
			(start -0.7874 -0.4064)
			(end 0.7874 -0.4064)
			(stroke
				(width 0.1524)
				(type default)
			)
			(layer "F.SilkS")
		)
		(fp_line
			(start -0.7874 0.4064)
			(end -0.7874 -0.4064)
			(stroke
				(width 0.1524)
				(type default)
			)
			(layer "F.SilkS")
		)
		(fp_line
			(start 0.7874 -0.4064)
			(end 0.7874 0.4064)
			(stroke
				(width 0.1524)
				(type default)
			)
			(layer "F.SilkS")
		)
		(fp_line
			(start 0.7874 0.4064)
			(end -0.7874 0.4064)
			(stroke
				(width 0.1524)
				(type default)
			)
			(layer "F.SilkS")
		)
		(fp_line
			(start -0.67945 -0.305054)
			(end -0.12065 -0.305054)
			(stroke
				(width 0.1)
				(type default)
			)
			(layer "F.Fab")
		)
		(fp_line
			(start -0.67945 0.3048)
			(end -0.67945 -0.305054)
			(stroke
				(width 0.1)
				(type default)
			)
			(layer "F.Fab")
		)
		(fp_line
			(start -0.12065 -0.305054)
			(end -0.12065 -0.2794)
			(stroke
				(width 0.1)
				(type default)
			)
			(layer "F.Fab")
		)
		(fp_line
			(start -0.12065 -0.2794)
			(end 0.12065 -0.2794)
			(stroke
				(width 0.1)
				(type default)
			)
			(layer "F.Fab")
		)
		(fp_line
			(start -0.12065 0.2794)
			(end -0.12065 0.3048)
			(stroke
				(width 0.1)
				(type default)
			)
			(layer "F.Fab")
		)
		(fp_line
			(start -0.12065 0.3048)
			(end -0.67945 0.3048)
			(stroke
				(width 0.1)
				(type default)
			)
			(layer "F.Fab")
		)
		(fp_line
			(start 0.120396 0.2794)
			(end -0.12065 0.2794)
			(stroke
				(width 0.1)
				(type default)
			)
			(layer "F.Fab")
		)
		(fp_line
			(start 0.120396 0.3048)
			(end 0.120396 0.2794)
			(stroke
				(width 0.1)
				(type default)
			)
			(layer "F.Fab")
		)
		(fp_line
			(start 0.12065 -0.3048)
			(end 0.67945 -0.3048)
			(stroke
				(width 0.1)
				(type default)
			)
			(layer "F.Fab")
		)
		(fp_line
			(start 0.12065 -0.2794)
			(end 0.12065 -0.3048)
			(stroke
				(width 0.1)
				(type default)
			)
			(layer "F.Fab")
		)
		(fp_line
			(start 0.67945 -0.3048)
			(end 0.67945 0.3048)
			(stroke
				(width 0.1)
				(type default)
			)
			(layer "F.Fab")
		)
		(fp_line
			(start 0.67945 0.3048)
			(end 0.120396 0.3048)
			(stroke
				(width 0.1)
				(type default)
			)
			(layer "F.Fab")
		)
		(pad "1" smd circle
			(at -0.40005 0)
			(size 0 0)
			(layers "F.Cu" "F.Mask" "F.Paste")
			(net "RST_PEX_NIC5_PERST_N")
		)
		(pad "2" smd circle
			(at 0.40005 0)
			(size 0 0)
			(layers "F.Cu" "F.Mask" "F.Paste")
			(net "RST_PEX_NIC5_PERST_R_N")
		)
	)
	(footprint ""
		(layer "F.Cu")
		(at 103.011224 -84.223606 180)
		(property "Reference" "R1470"
			(at 0 0 180)
			(layer "F.SilkS")
			(hide yes)
			(effects
				(font
					(size 1.27 1.27)
				)
			)
		)
		(property "Value" ""
			(at 0 0 180)
			(layer "F.Fab")
			(effects
				(font
					(size 1.27 1.27)
				)
			)
		)
		(duplicate_pad_numbers_are_jumpers no)
		(fp_line
			(start 0.7874 0.4064)
			(end -0.7874 0.4064)
			(stroke
				(width 0.1524)
				(type default)
			)
			(layer "F.SilkS")
		)
		(fp_line
			(start 0.7874 -0.4064)
			(end 0.7874 0.4064)
			(stroke
				(width 0.1524)
				(type default)
			)
			(layer "F.SilkS")
		)
		(fp_line
			(start -0.7874 0.4064)
			(end -0.7874 -0.4064)
			(stroke
				(width 0.1524)
				(type default)
			)
			(layer "F.SilkS")
		)
		(fp_line
			(start -0.7874 -0.4064)
			(end 0.7874 -0.4064)
			(stroke
				(width 0.1524)
				(type default)
			)
			(layer "F.SilkS")
		)
		(fp_line
			(start 0.67945 0.3048)
			(end 0.120396 0.3048)
			(stroke
				(width 0.1)
				(type default)
			)
			(layer "F.Fab")
		)
		(fp_line
			(start 0.67945 -0.3048)
			(end 0.67945 0.3048)
			(stroke
				(width 0.1)
				(type default)
			)
			(layer "F.Fab")
		)
		(fp_line
			(start 0.12065 -0.2794)
			(end 0.12065 -0.3048)
			(stroke
				(width 0.1)
				(type default)
			)
			(layer "F.Fab")
		)
		(fp_line
			(start 0.12065 -0.3048)
			(end 0.67945 -0.3048)
			(stroke
				(width 0.1)
				(type default)
			)
			(layer "F.Fab")
		)
		(fp_line
			(start 0.120396 0.3048)
			(end 0.120396 0.2794)
			(stroke
				(width 0.1)
				(type default)
			)
			(layer "F.Fab")
		)
		(fp_line
			(start 0.120396 0.2794)
			(end -0.12065 0.2794)
			(stroke
				(width 0.1)
				(type default)
			)
			(layer "F.Fab")
		)
		(fp_line
			(start -0.12065 0.3048)
			(end -0.67945 0.3048)
			(stroke
				(width 0.1)
				(type default)
			)
			(layer "F.Fab")
		)
		(fp_line
			(start -0.12065 0.2794)
			(end -0.12065 0.3048)
			(stroke
				(width 0.1)
				(type default)
			)
			(layer "F.Fab")
		)
		(fp_line
			(start -0.12065 -0.2794)
			(end 0.12065 -0.2794)
			(stroke
				(width 0.1)
				(type default)
			)
			(layer "F.Fab")
		)
		(fp_line
			(start -0.12065 -0.305054)
			(end -0.12065 -0.2794)
			(stroke
				(width 0.1)
				(type default)
			)
			(layer "F.Fab")
		)
		(fp_line
			(start -0.67945 0.3048)
			(end -0.67945 -0.305054)
			(stroke
				(width 0.1)
				(type default)
			)
			(layer "F.Fab")
		)
		(fp_line
			(start -0.67945 -0.305054)
			(end -0.12065 -0.305054)
			(stroke
				(width 0.1)
				(type default)
			)
			(layer "F.Fab")
		)
		(pad "1" smd circle
			(at -0.40005 0 180)
			(size 0 0)
			(layers "F.Cu" "F.Mask" "F.Paste")
			(net "SMB_BMC_9ZXL0851_0_7_SCL")
		)
		(pad "2" smd circle
			(at 0.40005 0 180)
			(size 0 0)
			(layers "F.Cu" "F.Mask" "F.Paste")
			(net "SMB_CLK_ISO_R_SCL")
		)
	)
)
